(kicad_pcb
	(version 20260206)
	(generator "pcbnew")
	(generator_version "10.0")
	(general
		(thickness 1.6)
		(legacy_teardrops no)
	)
	(paper "A4")
	(title_block
		(title "Bryce Canyon_R.DPB_16317-1_OCP.brd")
		(comment 1 "Bryce Canyon / footprints 1847-1854 of 2099")
	)
	(layers
		(0 "F.Cu" signal "TOP")
		(4 "In1.Cu" signal "L2GND")
		(6 "In2.Cu" signal "L3")
		(8 "In3.Cu" signal "L4VCC")
		(10 "In4.Cu" signal "L5VCC")
		(12 "In5.Cu" signal "L6")
		(14 "In6.Cu" signal "L7GND")
		(2 "B.Cu" signal "BOTTOM")
		(9 "F.Adhes" user "F.Adhesive")
		(11 "B.Adhes" user "B.Adhesive")
		(13 "F.Paste" user "Package Geometry/Pastemask Top")
		(15 "B.Paste" user "Package Geometry/Pastemask Bottom")
		(5 "F.SilkS" user "Ref Des/Silkscreen Top")
		(7 "B.SilkS" user "Ref Des/Silkscreen Bottom")
		(1 "F.Mask" user "Board Geometry/Soldermask Top")
		(3 "B.Mask" user "Board Geometry/Soldermask Bottom")
		(17 "Dwgs.User" user "User.Drawings")
		(19 "Cmts.User" user "User.Comments")
		(21 "Eco1.User" user "User.Eco1")
		(23 "Eco2.User" user "User.Eco2")
		(25 "Edge.Cuts" user "Board Geometry/Outline")
		(27 "Margin" user)
		(31 "F.CrtYd" user "Package Geometry/Place Bound Top")
		(29 "B.CrtYd" user "Package Geometry/Place Bound Bottom")
		(35 "F.Fab" user "Ref Des/Assembly Top")
		(33 "B.Fab" user "Ref Des/Assembly Bottom")
	)
	(footprint ""
		(layer "F.Cu")
		(at 46.33595 -217.337386 -90)
		(property "Reference" "R156"
			(at 0 0 270)
			(layer "F.SilkS")
			(hide yes)
			(effects
				(font
					(size 1.27 1.27)
				)
			)
		)
		(property "Value" "4K7R2F-GP"
			(at 0.064008 -3.993896 270)
			(unlocked yes)
			(layer "F.Fab")
			(hide yes)
			(effects
				(font
					(size 1.016 1.016)
					(thickness 0.1524)
				)
			)
		)
		(property "Device Type" "R402H16"
			(at 0.064008 -5.517896 270)
			(unlocked yes)
			(layer "F.Fab")
			(hide yes)
			(effects
				(font
					(size 1.016 1.016)
					(thickness 0.1524)
				)
			)
		)
		(duplicate_pad_numbers_are_jumpers no)
		(fp_line
			(start -0.508 -0.9398)
			(end -0.508 0.9398)
			(stroke
				(width 0.1524)
				(type default)
			)
			(layer "F.SilkS")
		)
		(fp_line
			(start 0.508 -0.9398)
			(end -0.508 -0.9398)
			(stroke
				(width 0.1524)
				(type default)
			)
			(layer "F.SilkS")
		)
		(fp_rect
			(start -0.508 0.9398)
			(end 0.508 -0.9398)
			(stroke
				(width 0)
				(type default)
			)
			(fill no)
			(layer "F.CrtYd")
		)
		(fp_rect
			(start -0.508 0.9398)
			(end 0.508 -0.9398)
			(stroke
				(width 0)
				(type default)
			)
			(fill no)
			(layer "F.Fab")
		)
		(pad "1" smd custom
			(at 0 -0.4445 270)
			(size 0.1397 0.1397)
			(layers "F.Cu" "F.Mask" "F.Paste")
			(net "DRIVE_B_1_FLT_LED")
			(options
				(clearance outline)
				(anchor circle)
			)
			(primitives
				(gr_poly
					(pts
						(arc
							(start -0.1778 -0.2794)
							(mid -0.249642 -0.249642)
							(end -0.2794 -0.1778)
						)
						(arc
							(start -0.2794 0.1778)
							(mid -0.249642 0.249642)
							(end -0.1778 0.2794)
						)
						(arc
							(start 0.1778 0.2794)
							(mid 0.249642 0.249642)
							(end 0.2794 0.1778)
						)
						(arc
							(start 0.2794 -0.1778)
							(mid 0.249642 -0.249642)
							(end 0.1778 -0.2794)
						)
					)
					(width 0)
					(fill yes)
				)
			)
		)
		(pad "2" smd custom
			(at 0 0.4445 270)
			(size 0.1397 0.1397)
			(layers "F.Cu" "F.Mask" "F.Paste")
			(net "GND")
			(options
				(clearance outline)
				(anchor circle)
			)
			(primitives
				(gr_poly
					(pts
						(arc
							(start -0.1778 -0.2794)
							(mid -0.249642 -0.249642)
							(end -0.2794 -0.1778)
						)
						(arc
							(start -0.2794 0.1778)
							(mid -0.249642 0.249642)
							(end -0.1778 0.2794)
						)
						(arc
							(start 0.1778 0.2794)
							(mid 0.249642 0.249642)
							(end 0.2794 0.1778)
						)
						(arc
							(start 0.2794 -0.1778)
							(mid 0.249642 -0.249642)
							(end 0.1778 -0.2794)
						)
					)
					(width 0)
					(fill yes)
				)
			)
		)
	)
	(footprint ""
		(layer "F.Cu")
		(at 407.093928 -217.413586 -90)
		(property "Reference" "R290"
			(at 0 0 270)
			(layer "F.SilkS")
			(hide yes)
			(effects
				(font
					(size 1.27 1.27)
				)
			)
		)
		(property "Value" "4K7R2F-GP"
			(at 0.064008 -3.993896 270)
			(unlocked yes)
			(layer "F.Fab")
			(hide yes)
			(effects
				(font
					(size 1.016 1.016)
					(thickness 0.1524)
				)
			)
		)
		(property "Device Type" "R402H16"
			(at 0.064008 -5.517896 270)
			(unlocked yes)
			(layer "F.Fab")
			(hide yes)
			(effects
				(font
					(size 1.016 1.016)
					(thickness 0.1524)
				)
			)
		)
		(duplicate_pad_numbers_are_jumpers no)
		(fp_line
			(start -0.508 -0.9398)
			(end -0.508 0.9398)
			(stroke
				(width 0.1524)
				(type default)
			)
			(layer "F.SilkS")
		)
		(fp_line
			(start 0.508 -0.9398)
			(end -0.508 -0.9398)
			(stroke
				(width 0.1524)
				(type default)
			)
			(layer "F.SilkS")
		)
		(fp_rect
			(start -0.508 0.9398)
			(end 0.508 -0.9398)
			(stroke
				(width 0)
				(type default)
			)
			(fill no)
			(layer "F.CrtYd")
		)
		(fp_rect
			(start -0.508 0.9398)
			(end 0.508 -0.9398)
			(stroke
				(width 0)
				(type default)
			)
			(fill no)
			(layer "F.Fab")
		)
		(pad "1" smd custom
			(at 0 -0.4445 270)
			(size 0.1397 0.1397)
			(layers "F.Cu" "F.Mask" "F.Paste")
			(net "DRIVE_B_9_FLT_LED")
			(options
				(clearance outline)
				(anchor circle)
			)
			(primitives
				(gr_poly
					(pts
						(arc
							(start -0.1778 -0.2794)
							(mid -0.249642 -0.249642)
							(end -0.2794 -0.1778)
						)
						(arc
							(start -0.2794 0.1778)
							(mid -0.249642 0.249642)
							(end -0.1778 0.2794)
						)
						(arc
							(start 0.1778 0.2794)
							(mid 0.249642 0.249642)
							(end 0.2794 0.1778)
						)
						(arc
							(start 0.2794 -0.1778)
							(mid 0.249642 -0.249642)
							(end 0.1778 -0.2794)
						)
					)
					(width 0)
					(fill yes)
				)
			)
		)
		(pad "2" smd custom
			(at 0 0.4445 270)
			(size 0.1397 0.1397)
			(layers "F.Cu" "F.Mask" "F.Paste")
			(net "GND")
			(options
				(clearance outline)
				(anchor circle)
			)
			(primitives
				(gr_poly
					(pts
						(arc
							(start -0.1778 -0.2794)
							(mid -0.249642 -0.249642)
							(end -0.2794 -0.1778)
						)
						(arc
							(start -0.2794 0.1778)
							(mid -0.249642 0.249642)
							(end -0.1778 0.2794)
						)
						(arc
							(start 0.1778 0.2794)
							(mid 0.249642 0.249642)
							(end 0.2794 0.1778)
						)
						(arc
							(start 0.2794 -0.1778)
							(mid 0.249642 -0.249642)
							(end 0.1778 -0.2794)
						)
					)
					(width 0)
					(fill yes)
				)
			)
		)
	)
	(footprint ""
		(layer "F.Cu")
		(at 458.505814 -378.4854 -90)
		(property "Reference" "R1304"
			(at 0 0 270)
			(layer "F.SilkS")
			(hide yes)
			(effects
				(font
					(size 1.27 1.27)
				)
			)
		)
		(property "Value" "4K7R2F-GP"
			(at 0.064008 -3.993896 270)
			(unlocked yes)
			(layer "F.Fab")
			(hide yes)
			(effects
				(font
					(size 1.016 1.016)
					(thickness 0.1524)
				)
			)
		)
		(property "Device Type" "R402H16"
			(at 0.064008 -5.517896 270)
			(unlocked yes)
			(layer "F.Fab")
			(hide yes)
			(effects
				(font
					(size 1.016 1.016)
					(thickness 0.1524)
				)
			)
		)
		(duplicate_pad_numbers_are_jumpers no)
		(fp_line
			(start -0.508 -0.9398)
			(end -0.508 0.9398)
			(stroke
				(width 0.1524)
				(type default)
			)
			(layer "F.SilkS")
		)
		(fp_line
			(start 0.508 -0.9398)
			(end -0.508 -0.9398)
			(stroke
				(width 0.1524)
				(type default)
			)
			(layer "F.SilkS")
		)
		(fp_rect
			(start -0.508 0.9398)
			(end 0.508 -0.9398)
			(stroke
				(width 0)
				(type default)
			)
			(fill no)
			(layer "F.CrtYd")
		)
		(fp_rect
			(start -0.508 0.9398)
			(end 0.508 -0.9398)
			(stroke
				(width 0)
				(type default)
			)
			(fill no)
			(layer "F.Fab")
		)
		(pad "1" smd custom
			(at 0 -0.4445 270)
			(size 0.1397 0.1397)
			(layers "F.Cu" "F.Mask" "F.Paste")
			(net "FAN_BLUE_LED3")
			(options
				(clearance outline)
				(anchor circle)
			)
			(primitives
				(gr_poly
					(pts
						(arc
							(start -0.1778 -0.2794)
							(mid -0.249642 -0.249642)
							(end -0.2794 -0.1778)
						)
						(arc
							(start -0.2794 0.1778)
							(mid -0.249642 0.249642)
							(end -0.1778 0.2794)
						)
						(arc
							(start 0.1778 0.2794)
							(mid 0.249642 0.249642)
							(end 0.2794 0.1778)
						)
						(arc
							(start 0.2794 -0.1778)
							(mid 0.249642 -0.249642)
							(end 0.1778 -0.2794)
						)
					)
					(width 0)
					(fill yes)
				)
			)
		)
		(pad "2" smd custom
			(at 0 0.4445 270)
			(size 0.1397 0.1397)
			(layers "F.Cu" "F.Mask" "F.Paste")
			(net "FAN_LED3_D")
			(options
				(clearance outline)
				(anchor circle)
			)
			(primitives
				(gr_poly
					(pts
						(arc
							(start -0.1778 -0.2794)
							(mid -0.249642 -0.249642)
							(end -0.2794 -0.1778)
						)
						(arc
							(start -0.2794 0.1778)
							(mid -0.249642 0.249642)
							(end -0.1778 0.2794)
						)
						(arc
							(start 0.1778 0.2794)
							(mid 0.249642 0.249642)
							(end 0.2794 0.1778)
						)
						(arc
							(start 0.2794 -0.1778)
							(mid 0.249642 -0.249642)
							(end 0.1778 -0.2794)
						)
					)
					(width 0)
					(fill yes)
				)
			)
		)
	)
	(footprint ""
		(layer "F.Cu")
		(at 436.089044 -111.731552 90)
		(property "Reference" "C676"
			(at 0 0 90)
			(layer "F.SilkS")
			(hide yes)
			(effects
				(font
					(size 1.27 1.27)
				)
			)
		)
		(property "Value" "SC10U16V5KX-7-GP-U"
			(at -0.0762 -6.1214 90)
			(unlocked yes)
			(layer "F.Fab")
			(hide yes)
			(effects
				(font
					(size 1.016 1.016)
					(thickness 0.1524)
				)
			)
		)
		(property "Device Type" "C805H58"
			(at -0.0762 -8.1534 90)
			(unlocked yes)
			(layer "F.Fab")
			(hide yes)
			(effects
				(font
					(size 1.016 1.016)
					(thickness 0.1524)
				)
			)
		)
		(duplicate_pad_numbers_are_jumpers no)
		(fp_line
			(start 0.635 0)
			(end -0.635 0)
			(stroke
				(width 0.508)
				(type default)
			)
			(layer "F.SilkS")
		)
		(fp_rect
			(start -0.9652 1.778)
			(end 0.9652 -1.778)
			(stroke
				(width 0)
				(type default)
			)
			(fill no)
			(layer "F.CrtYd")
		)
		(fp_poly
			(pts
				(xy -0.9652 -1.778) (xy 0.9652 -1.778) (xy 0.9652 1.778) (xy -0.9652 1.778)
			)
			(stroke
				(width 0)
				(type default)
			)
			(fill no)
			(layer "F.Fab")
		)
		(pad "1" smd rect
			(at 0 -0.9652 90)
			(size 1.397 1.143)
			(layers "F.Cu" "F.Mask" "F.Paste")
			(net "P12V_B_4_VIN_U34")
		)
		(pad "2" smd rect
			(at 0 0.9652 90)
			(size 1.397 1.143)
			(layers "F.Cu" "F.Mask" "F.Paste")
			(net "GND")
		)
	)
	(footprint ""
		(layer "F.Cu")
		(at 165.224968 -99.798378 90)
		(property "Reference" "Q259"
			(at 0 0 90)
			(layer "F.SilkS")
			(hide yes)
			(effects
				(font
					(size 1.27 1.27)
				)
			)
		)
		(property "Value" "SSM3K324R-GP"
			(at 0.127 -8.9662 90)
			(unlocked yes)
			(layer "F.Fab")
			(hide yes)
			(effects
				(font
					(size 1.016 1.016)
					(thickness 0.1524)
				)
			)
		)
		(property "Device Type" "SOT23DGS2D4H35"
			(at 0.127 -10.4902 90)
			(unlocked yes)
			(layer "F.Fab")
			(hide yes)
			(effects
				(font
					(size 1.016 1.016)
					(thickness 0.1524)
				)
			)
		)
		(duplicate_pad_numbers_are_jumpers no)
		(fp_line
			(start 1.651 -1.778)
			(end -1.651 -1.778)
			(stroke
				(width 0.1524)
				(type default)
			)
			(layer "F.SilkS")
		)
		(fp_line
			(start -1.651 -1.778)
			(end -1.651 1.778)
			(stroke
				(width 0.1524)
				(type default)
			)
			(layer "F.SilkS")
		)
		(fp_line
			(start 1.651 1.778)
			(end 1.651 -1.778)
			(stroke
				(width 0.1524)
				(type default)
			)
			(layer "F.SilkS")
		)
		(fp_line
			(start -1.651 1.778)
			(end 1.651 1.778)
			(stroke
				(width 0.1524)
				(type default)
			)
			(layer "F.SilkS")
		)
		(fp_poly
			(pts
				(xy -1.778 1.8796) (xy -1.778 -1.8796) (xy 1.778 -1.8796) (xy 1.778 1.8796)
			)
			(stroke
				(width 0)
				(type default)
			)
			(fill no)
			(layer "F.CrtYd")
		)
		(fp_poly
			(pts
				(xy -1.778 1.8796) (xy -1.778 -1.8796) (xy 1.778 -1.8796) (xy 1.778 1.8796)
			)
			(stroke
				(width 0)
				(type default)
			)
			(fill no)
			(layer "F.Fab")
		)
		(pad "D" smd custom
			(at 0 -0.9525 90)
			(size 0.1905 0.1905)
			(layers "F.Cu" "F.Mask" "F.Paste")
			(net "DRV_ACT_17_N")
			(options
				(clearance outline)
				(anchor circle)
			)
			(primitives
				(gr_poly
					(pts
						(arc
							(start -0.1778 0.5715)
							(mid -0.321484 0.511984)
							(end -0.381 0.3683)
						)
						(arc
							(start -0.381 -0.3683)
							(mid -0.321484 -0.511984)
							(end -0.1778 -0.5715)
						)
						(arc
							(start 0.1778 -0.5715)
							(mid 0.321484 -0.511984)
							(end 0.381 -0.3683)
						)
						(arc
							(start 0.381 0.3683)
							(mid 0.321484 0.511984)
							(end 0.1778 0.5715)
						)
					)
					(width 0)
					(fill yes)
				)
			)
		)
		(pad "G" smd custom
			(at -0.98425 0.9525 90)
			(size 0.1905 0.1905)
			(layers "F.Cu" "F.Mask" "F.Paste")
			(net "DRIVE_B_17_ACT")
			(options
				(clearance outline)
				(anchor circle)
			)
			(primitives
				(gr_poly
					(pts
						(arc
							(start -0.1778 0.5715)
							(mid -0.321484 0.511984)
							(end -0.381 0.3683)
						)
						(arc
							(start -0.381 -0.3683)
							(mid -0.321484 -0.511984)
							(end -0.1778 -0.5715)
						)
						(arc
							(start 0.1778 -0.5715)
							(mid 0.321484 -0.511984)
							(end 0.381 -0.3683)
						)
						(arc
							(start 0.381 0.3683)
							(mid 0.321484 0.511984)
							(end 0.1778 0.5715)
						)
					)
					(width 0)
					(fill yes)
				)
			)
		)
		(pad "S" smd custom
			(at 0.98425 0.9525 90)
			(size 0.1905 0.1905)
			(layers "F.Cu" "F.Mask" "F.Paste")
			(net "GND")
			(options
				(clearance outline)
				(anchor circle)
			)
			(primitives
				(gr_poly
					(pts
						(arc
							(start -0.1778 0.5715)
							(mid -0.321484 0.511984)
							(end -0.381 0.3683)
						)
						(arc
							(start -0.381 -0.3683)
							(mid -0.321484 -0.511984)
							(end -0.1778 -0.5715)
						)
						(arc
							(start 0.1778 -0.5715)
							(mid 0.321484 -0.511984)
							(end 0.381 -0.3683)
						)
						(arc
							(start 0.381 0.3683)
							(mid 0.321484 0.511984)
							(end 0.1778 0.5715)
						)
					)
					(width 0)
					(fill yes)
				)
			)
		)
	)
	(footprint ""
		(layer "F.Cu")
		(at 29.457396 -376.0216 90)
		(property "Reference" "R173"
			(at 0 0 90)
			(layer "F.SilkS")
			(hide yes)
			(effects
				(font
					(size 1.27 1.27)
				)
			)
		)
		(property "Value" "4K7R2F-GP"
			(at 0.064008 -3.993896 90)
			(unlocked yes)
			(layer "F.Fab")
			(hide yes)
			(effects
				(font
					(size 1.016 1.016)
					(thickness 0.1524)
				)
			)
		)
		(property "Device Type" "R402H16"
			(at 0.064008 -5.517896 90)
			(unlocked yes)
			(layer "F.Fab")
			(hide yes)
			(effects
				(font
					(size 1.016 1.016)
					(thickness 0.1524)
				)
			)
		)
		(duplicate_pad_numbers_are_jumpers no)
		(fp_line
			(start 0.508 -0.9398)
			(end -0.508 -0.9398)
			(stroke
				(width 0.1524)
				(type default)
			)
			(layer "F.SilkS")
		)
		(fp_line
			(start -0.508 -0.9398)
			(end -0.508 0.9398)
			(stroke
				(width 0.1524)
				(type default)
			)
			(layer "F.SilkS")
		)
		(fp_rect
			(start -0.508 0.9398)
			(end 0.508 -0.9398)
			(stroke
				(width 0)
				(type default)
			)
			(fill no)
			(layer "F.CrtYd")
		)
		(fp_rect
			(start -0.508 0.9398)
			(end 0.508 -0.9398)
			(stroke
				(width 0)
				(type default)
			)
			(fill no)
			(layer "F.Fab")
		)
		(pad "1" smd custom
			(at 0 -0.4445 90)
			(size 0.1397 0.1397)
			(layers "F.Cu" "F.Mask" "F.Paste")
			(net "FAN_BLUE_LED0")
			(options
				(clearance outline)
				(anchor circle)
			)
			(primitives
				(gr_poly
					(pts
						(arc
							(start -0.1778 -0.2794)
							(mid -0.249642 -0.249642)
							(end -0.2794 -0.1778)
						)
						(arc
							(start -0.2794 0.1778)
							(mid -0.249642 0.249642)
							(end -0.1778 0.2794)
						)
						(arc
							(start 0.1778 0.2794)
							(mid 0.249642 0.249642)
							(end 0.2794 0.1778)
						)
						(arc
							(start 0.2794 -0.1778)
							(mid 0.249642 -0.249642)
							(end 0.1778 -0.2794)
						)
					)
					(width 0)
					(fill yes)
				)
			)
		)
		(pad "2" smd custom
			(at 0 0.4445 90)
			(size 0.1397 0.1397)
			(layers "F.Cu" "F.Mask" "F.Paste")
			(net "P12V_IN")
			(options
				(clearance outline)
				(anchor circle)
			)
			(primitives
				(gr_poly
					(pts
						(arc
							(start -0.1778 -0.2794)
							(mid -0.249642 -0.249642)
							(end -0.2794 -0.1778)
						)
						(arc
							(start -0.2794 0.1778)
							(mid -0.249642 0.249642)
							(end -0.1778 0.2794)
						)
						(arc
							(start 0.1778 0.2794)
							(mid 0.249642 0.249642)
							(end 0.2794 0.1778)
						)
						(arc
							(start 0.2794 -0.1778)
							(mid 0.249642 -0.249642)
							(end 0.1778 -0.2794)
						)
					)
					(width 0)
					(fill yes)
				)
			)
		)
	)
	(footprint ""
		(layer "F.Cu")
		(at 413.866076 -154.70505)
		(property "Reference" "TP126"
			(at 0 0 0)
			(layer "F.SilkS")
			(hide yes)
			(effects
				(font
					(size 1.27 1.27)
				)
			)
		)
		(property "Value" "*"
			(at -0.0508 -1.6764 0)
			(unlocked yes)
			(layer "F.Fab")
			(hide yes)
			(effects
				(font
					(size 1.016 1.016)
					(thickness 0.1524)
				)
			)
		)
		(property "Device Type" "TPAD32"
			(at -0.0508 -3.2004 0)
			(unlocked yes)
			(layer "F.Fab")
			(hide yes)
			(effects
				(font
					(size 1.016 1.016)
					(thickness 0.1524)
				)
			)
		)
		(duplicate_pad_numbers_are_jumpers no)
		(fp_poly
			(pts
				(arc
					(start 0.4064 0)
					(mid -0.4064 0)
					(end 0.4064 0)
				)
			)
			(stroke
				(width 0)
				(type default)
			)
			(fill no)
			(layer "F.CrtYd")
		)
		(fp_poly
			(pts
				(arc
					(start 0.7112 0)
					(mid -0.7112 0)
					(end 0.7112 0)
				)
			)
			(stroke
				(width 0)
				(type default)
			)
			(fill no)
			(layer "F.Fab")
		)
		(pad "1" smd circle
			(at 0 0)
			(size 0.8128 0.8128)
			(layers "F.Cu" "F.Mask" "F.Paste")
			(net "ACT_HDD_21")
		)
	)
	(footprint ""
		(layer "F.Cu")
		(at 23.749 -263.271)
		(property "Reference" "R897"
			(at 0 0 0)
			(layer "F.SilkS")
			(hide yes)
			(effects
				(font
					(size 1.27 1.27)
				)
			)
		)
		(property "Value" "2R6F-GP"
			(at -0.0508 -4.8514 0)
			(unlocked yes)
			(layer "F.Fab")
			(hide yes)
			(effects
				(font
					(size 1.016 1.016)
					(thickness 0.1524)
				)
			)
		)
		(property "Device Type" "R1206H26"
			(at 0 -6.3754 0)
			(unlocked yes)
			(layer "F.Fab")
			(hide yes)
			(effects
				(font
					(size 1.016 1.016)
					(thickness 0.1524)
				)
			)
		)
		(duplicate_pad_numbers_are_jumpers no)
		(fp_line
			(start -1.016 -2.2352)
			(end 1.016 -2.2352)
			(stroke
				(width 0.1524)
				(type default)
			)
			(layer "F.SilkS")
		)
		(fp_line
			(start -1.016 2.2352)
			(end -1.016 -2.2352)
			(stroke
				(width 0.1524)
				(type default)
			)
			(layer "F.SilkS")
		)
		(fp_line
			(start 1.016 -2.2352)
			(end 1.016 2.2352)
			(stroke
				(width 0.1524)
				(type default)
			)
			(layer "F.SilkS")
		)
		(fp_line
			(start 1.016 2.2352)
			(end -1.016 2.2352)
			(stroke
				(width 0.1524)
				(type default)
			)
			(layer "F.SilkS")
		)
		(fp_rect
			(start -1.0922 2.3114)
			(end 1.0922 -2.3114)
			(stroke
				(width 0)
				(type default)
			)
			(fill no)
			(layer "F.CrtYd")
		)
		(fp_poly
			(pts
				(xy -1.0922 -2.3114) (xy 1.0922 -2.3114) (xy 1.0922 2.3114) (xy -1.0922 2.3114)
			)
			(stroke
				(width 0)
				(type default)
			)
			(fill no)
			(layer "F.Fab")
		)
		(pad "1" smd rect
			(at 0 -1.397)
			(size 1.651 1.27)
			(layers "F.Cu" "F.Mask" "F.Paste")
			(net "P5V_HDD0")
		)
		(pad "2" smd rect
			(at 0 1.397)
			(size 1.651 1.27)
			(layers "F.Cu" "F.Mask" "F.Paste")
			(net "5V_PRE_0")
		)
	)
)
